(kicad_pcb
	(version 20260206)
	(generator "pcbnew")
	(generator_version "10.0")
	(general
		(thickness 1.6)
		(legacy_teardrops no)
	)
	(paper "A4")
	(title_block
		(title "Bryce Canyon_F.DPB_16315-1-OCP.brd")
		(comment 1 "Bryce Canyon / footprints 1152-1159 of 2223")
	)
	(layers
		(0 "F.Cu" signal "TOP")
		(4 "In1.Cu" signal "L2GND")
		(6 "In2.Cu" signal "L3")
		(8 "In3.Cu" signal "L4GND")
		(10 "In4.Cu" signal "L5")
		(12 "In5.Cu" signal "L6VCC")
		(14 "In6.Cu" signal "L7VCC")
		(16 "In7.Cu" signal "L8")
		(18 "In8.Cu" signal "L9GND")
		(20 "In9.Cu" signal "L10")
		(22 "In10.Cu" signal "L11GND")
		(2 "B.Cu" signal "BOTTOM")
		(9 "F.Adhes" user "F.Adhesive")
		(11 "B.Adhes" user "B.Adhesive")
		(13 "F.Paste" user "Package Geometry/Pastemask Top")
		(15 "B.Paste" user "Package Geometry/Pastemask Bottom")
		(5 "F.SilkS" user "Ref Des/Silkscreen Top")
		(7 "B.SilkS" user "Ref Des/Silkscreen Bottom")
		(1 "F.Mask" user "Board Geometry/Soldermask Top")
		(3 "B.Mask" user "Board Geometry/Soldermask Bottom")
		(17 "Dwgs.User" user "User.Drawings")
		(19 "Cmts.User" user "User.Comments")
		(21 "Eco1.User" user "User.Eco1")
		(23 "Eco2.User" user "User.Eco2")
		(25 "Edge.Cuts" user "Board Geometry/Outline")
		(27 "Margin" user)
		(31 "F.CrtYd" user "Package Geometry/Place Bound Top")
		(29 "B.CrtYd" user "Package Geometry/Place Bound Bottom")
		(35 "F.Fab" user "Ref Des/Assembly Top")
		(33 "B.Fab" user "Ref Des/Assembly Bottom")
	)
	(footprint ""
		(layer "F.Cu")
		(at 150.057866 -143.848074 90)
		(property "Reference" "R1056"
			(at 0 0 90)
			(layer "F.SilkS")
			(hide yes)
			(effects
				(font
					(size 1.27 1.27)
				)
			)
		)
		(property "Value" "100KR2F-L1-GP"
			(at 0.064008 -3.993896 90)
			(unlocked yes)
			(layer "F.Fab")
			(hide yes)
			(effects
				(font
					(size 1.016 1.016)
					(thickness 0.1524)
				)
			)
		)
		(property "Device Type" "R402H16"
			(at 0.064008 -5.517896 90)
			(unlocked yes)
			(layer "F.Fab")
			(hide yes)
			(effects
				(font
					(size 1.016 1.016)
					(thickness 0.1524)
				)
			)
		)
		(duplicate_pad_numbers_are_jumpers no)
		(fp_line
			(start 0.508 -0.9398)
			(end -0.508 -0.9398)
			(stroke
				(width 0.1524)
				(type default)
			)
			(layer "F.SilkS")
		)
		(fp_line
			(start -0.508 -0.9398)
			(end -0.508 0.9398)
			(stroke
				(width 0.1524)
				(type default)
			)
			(layer "F.SilkS")
		)
		(fp_rect
			(start -0.508 0.9398)
			(end 0.508 -0.9398)
			(stroke
				(width 0)
				(type default)
			)
			(fill no)
			(layer "F.CrtYd")
		)
		(fp_rect
			(start -0.508 0.9398)
			(end 0.508 -0.9398)
			(stroke
				(width 0)
				(type default)
			)
			(fill no)
			(layer "F.Fab")
		)
		(pad "1" smd custom
			(at 0 -0.4445 90)
			(size 0.1397 0.1397)
			(layers "F.Cu" "F.Mask" "F.Paste")
			(net "MB0_VCAP_R")
			(options
				(clearance outline)
				(anchor circle)
			)
			(primitives
				(gr_poly
					(pts
						(arc
							(start -0.1778 -0.2794)
							(mid -0.249642 -0.249642)
							(end -0.2794 -0.1778)
						)
						(arc
							(start -0.2794 0.1778)
							(mid -0.249642 0.249642)
							(end -0.1778 0.2794)
						)
						(arc
							(start 0.1778 0.2794)
							(mid 0.249642 0.249642)
							(end 0.2794 0.1778)
						)
						(arc
							(start 0.2794 -0.1778)
							(mid 0.249642 -0.249642)
							(end 0.1778 -0.2794)
						)
					)
					(width 0)
					(fill yes)
				)
			)
		)
		(pad "2" smd custom
			(at 0 0.4445 90)
			(size 0.1397 0.1397)
			(layers "F.Cu" "F.Mask" "F.Paste")
			(net "MB0_PSET_R")
			(options
				(clearance outline)
				(anchor circle)
			)
			(primitives
				(gr_poly
					(pts
						(arc
							(start -0.1778 -0.2794)
							(mid -0.249642 -0.249642)
							(end -0.2794 -0.1778)
						)
						(arc
							(start -0.2794 0.1778)
							(mid -0.249642 0.249642)
							(end -0.1778 0.2794)
						)
						(arc
							(start 0.1778 0.2794)
							(mid 0.249642 0.249642)
							(end 0.2794 0.1778)
						)
						(arc
							(start 0.2794 -0.1778)
							(mid 0.249642 -0.249642)
							(end 0.1778 -0.2794)
						)
					)
					(width 0)
					(fill yes)
				)
			)
		)
	)
	(footprint ""
		(layer "F.Cu")
		(at 400.03095 -275.760942 180)
		(property "Reference" "R328"
			(at 0 0 180)
			(layer "F.SilkS")
			(hide yes)
			(effects
				(font
					(size 1.27 1.27)
				)
			)
		)
		(property "Value" "4K7R2J-2-GP"
			(at 0.064008 -3.993896 180)
			(unlocked yes)
			(layer "F.Fab")
			(hide yes)
			(effects
				(font
					(size 1.016 1.016)
					(thickness 0.1524)
				)
			)
		)
		(property "Device Type" "R402H16"
			(at 0.064008 -5.517896 180)
			(unlocked yes)
			(layer "F.Fab")
			(hide yes)
			(effects
				(font
					(size 1.016 1.016)
					(thickness 0.1524)
				)
			)
		)
		(duplicate_pad_numbers_are_jumpers no)
		(fp_line
			(start 0.508 -0.9398)
			(end -0.508 -0.9398)
			(stroke
				(width 0.1524)
				(type default)
			)
			(layer "F.SilkS")
		)
		(fp_line
			(start -0.508 -0.9398)
			(end -0.508 0.9398)
			(stroke
				(width 0.1524)
				(type default)
			)
			(layer "F.SilkS")
		)
		(fp_rect
			(start -0.508 0.9398)
			(end 0.508 -0.9398)
			(stroke
				(width 0)
				(type default)
			)
			(fill no)
			(layer "F.CrtYd")
		)
		(fp_rect
			(start -0.508 0.9398)
			(end 0.508 -0.9398)
			(stroke
				(width 0)
				(type default)
			)
			(fill no)
			(layer "F.Fab")
		)
		(pad "1" smd custom
			(at 0 -0.4445 180)
			(size 0.1397 0.1397)
			(layers "F.Cu" "F.Mask" "F.Paste")
			(net "P12V_A")
			(options
				(clearance outline)
				(anchor circle)
			)
			(primitives
				(gr_poly
					(pts
						(arc
							(start -0.1778 -0.2794)
							(mid -0.249642 -0.249642)
							(end -0.2794 -0.1778)
						)
						(arc
							(start -0.2794 0.1778)
							(mid -0.249642 0.249642)
							(end -0.1778 0.2794)
						)
						(arc
							(start 0.1778 0.2794)
							(mid 0.249642 0.249642)
							(end 0.2794 0.1778)
						)
						(arc
							(start 0.2794 -0.1778)
							(mid 0.249642 -0.249642)
							(end 0.1778 -0.2794)
						)
					)
					(width 0)
					(fill yes)
				)
			)
		)
		(pad "2" smd custom
			(at 0 0.4445 180)
			(size 0.1397 0.1397)
			(layers "F.Cu" "F.Mask" "F.Paste")
			(net "SW_HDD_R8")
			(options
				(clearance outline)
				(anchor circle)
			)
			(primitives
				(gr_poly
					(pts
						(arc
							(start -0.1778 -0.2794)
							(mid -0.249642 -0.249642)
							(end -0.2794 -0.1778)
						)
						(arc
							(start -0.2794 0.1778)
							(mid -0.249642 0.249642)
							(end -0.1778 0.2794)
						)
						(arc
							(start 0.1778 0.2794)
							(mid 0.249642 0.249642)
							(end 0.2794 0.1778)
						)
						(arc
							(start 0.2794 -0.1778)
							(mid 0.249642 -0.249642)
							(end 0.1778 -0.2794)
						)
					)
					(width 0)
					(fill yes)
				)
			)
		)
	)
	(footprint ""
		(layer "F.Cu")
		(at 478.30359 -269.224252 -90)
		(property "Reference" "R383"
			(at 0 0 270)
			(layer "F.SilkS")
			(hide yes)
			(effects
				(font
					(size 1.27 1.27)
				)
			)
		)
		(property "Value" "10KR2F-2-GP"
			(at 0.064008 -3.993896 270)
			(unlocked yes)
			(layer "F.Fab")
			(hide yes)
			(effects
				(font
					(size 1.016 1.016)
					(thickness 0.1524)
				)
			)
		)
		(property "Device Type" "R402H16"
			(at 0.064008 -5.517896 270)
			(unlocked yes)
			(layer "F.Fab")
			(hide yes)
			(effects
				(font
					(size 1.016 1.016)
					(thickness 0.1524)
				)
			)
		)
		(duplicate_pad_numbers_are_jumpers no)
		(fp_line
			(start -0.508 -0.9398)
			(end -0.508 0.9398)
			(stroke
				(width 0.1524)
				(type default)
			)
			(layer "F.SilkS")
		)
		(fp_line
			(start 0.508 -0.9398)
			(end -0.508 -0.9398)
			(stroke
				(width 0.1524)
				(type default)
			)
			(layer "F.SilkS")
		)
		(fp_rect
			(start -0.508 0.9398)
			(end 0.508 -0.9398)
			(stroke
				(width 0)
				(type default)
			)
			(fill no)
			(layer "F.CrtYd")
		)
		(fp_rect
			(start -0.508 0.9398)
			(end 0.508 -0.9398)
			(stroke
				(width 0)
				(type default)
			)
			(fill no)
			(layer "F.Fab")
		)
		(pad "1" smd custom
			(at 0 -0.4445 270)
			(size 0.1397 0.1397)
			(layers "F.Cu" "F.Mask" "F.Paste")
			(net "P3V3_STBY_A")
			(options
				(clearance outline)
				(anchor circle)
			)
			(primitives
				(gr_poly
					(pts
						(arc
							(start -0.1778 -0.2794)
							(mid -0.249642 -0.249642)
							(end -0.2794 -0.1778)
						)
						(arc
							(start -0.2794 0.1778)
							(mid -0.249642 0.249642)
							(end -0.1778 0.2794)
						)
						(arc
							(start 0.1778 0.2794)
							(mid 0.249642 0.249642)
							(end 0.2794 0.1778)
						)
						(arc
							(start 0.2794 -0.1778)
							(mid 0.249642 -0.249642)
							(end 0.1778 -0.2794)
						)
					)
					(width 0)
					(fill yes)
				)
			)
		)
		(pad "2" smd custom
			(at 0 0.4445 270)
			(size 0.1397 0.1397)
			(layers "F.Cu" "F.Mask" "F.Paste")
			(net "HDD_PRSNT_11")
			(options
				(clearance outline)
				(anchor circle)
			)
			(primitives
				(gr_poly
					(pts
						(arc
							(start -0.1778 -0.2794)
							(mid -0.249642 -0.249642)
							(end -0.2794 -0.1778)
						)
						(arc
							(start -0.2794 0.1778)
							(mid -0.249642 0.249642)
							(end -0.1778 0.2794)
						)
						(arc
							(start 0.1778 0.2794)
							(mid 0.249642 0.249642)
							(end 0.2794 0.1778)
						)
						(arc
							(start 0.2794 -0.1778)
							(mid 0.249642 -0.249642)
							(end 0.1778 -0.2794)
						)
					)
					(width 0)
					(fill yes)
				)
			)
		)
	)
	(footprint ""
		(layer "F.Cu")
		(at 262.017002 -218.021662)
		(property "Reference" "C56"
			(at 0 0 0)
			(layer "F.SilkS")
			(hide yes)
			(effects
				(font
					(size 1.27 1.27)
				)
			)
		)
		(property "Value" "SCD1U16V2KX-3GP"
			(at 1.1811 -2.7051 0)
			(unlocked yes)
			(layer "F.Fab")
			(hide yes)
			(effects
				(font
					(size 1.016 1.016)
					(thickness 0.1524)
				)
			)
		)
		(property "Device Type" "C402H22"
			(at 1.1811 -4.2291 0)
			(unlocked yes)
			(layer "F.Fab")
			(hide yes)
			(effects
				(font
					(size 1.016 1.016)
					(thickness 0.1524)
				)
			)
		)
		(duplicate_pad_numbers_are_jumpers no)
		(fp_rect
			(start -0.4318 0.9525)
			(end 0.4318 -0.9525)
			(stroke
				(width 0)
				(type default)
			)
			(fill no)
			(layer "F.CrtYd")
		)
		(fp_rect
			(start -0.4318 0.9525)
			(end 0.4318 -0.9525)
			(stroke
				(width 0)
				(type default)
			)
			(fill no)
			(layer "F.Fab")
		)
		(pad "1" smd custom
			(at 0 -0.4445)
			(size 0.1524 0.1524)
			(layers "F.Cu" "F.Mask" "F.Paste")
			(net "P3V3_STBY_A")
			(options
				(clearance outline)
				(anchor circle)
			)
			(primitives
				(gr_poly
					(pts
						(arc
							(start 0.3048 -0.2032)
							(mid 0.275042 -0.275042)
							(end 0.2032 -0.3048)
						)
						(arc
							(start -0.2032 -0.3048)
							(mid -0.275042 -0.275042)
							(end -0.3048 -0.2032)
						)
						(arc
							(start -0.3048 0.2032)
							(mid -0.275042 0.275042)
							(end -0.2032 0.3048)
						)
						(arc
							(start 0.2032 0.3048)
							(mid 0.275042 0.275042)
							(end 0.3048 0.2032)
						)
					)
					(width 0)
					(fill yes)
				)
			)
		)
		(pad "2" smd custom
			(at 0 0.4445)
			(size 0.1524 0.1524)
			(layers "F.Cu" "F.Mask" "F.Paste")
			(net "GND")
			(options
				(clearance outline)
				(anchor circle)
			)
			(primitives
				(gr_poly
					(pts
						(arc
							(start 0.3048 -0.2032)
							(mid 0.275042 -0.275042)
							(end 0.2032 -0.3048)
						)
						(arc
							(start -0.2032 -0.3048)
							(mid -0.275042 -0.275042)
							(end -0.3048 -0.2032)
						)
						(arc
							(start -0.3048 0.2032)
							(mid -0.275042 0.275042)
							(end -0.2032 0.3048)
						)
						(arc
							(start 0.2032 0.3048)
							(mid 0.275042 0.275042)
							(end 0.3048 0.2032)
						)
					)
					(width 0)
					(fill yes)
				)
			)
		)
	)
	(footprint ""
		(layer "F.Cu")
		(at 114.699796 -176.000918 -90)
		(property "Reference" "C236"
			(at 0 0 270)
			(layer "F.SilkS")
			(hide yes)
			(effects
				(font
					(size 1.27 1.27)
				)
			)
		)
		(property "Value" "SC10U16V6KX-2GP"
			(at -0.0762 -5.1308 270)
			(unlocked yes)
			(layer "F.Fab")
			(hide yes)
			(effects
				(font
					(size 1.016 1.016)
					(thickness 0.1524)
				)
			)
		)
		(property "Device Type" "C1206H71"
			(at -0.127 -6.6548 270)
			(unlocked yes)
			(layer "F.Fab")
			(hide yes)
			(effects
				(font
					(size 1.016 1.016)
					(thickness 0.1524)
				)
			)
		)
		(duplicate_pad_numbers_are_jumpers no)
		(fp_line
			(start -1.016 2.2352)
			(end -1.016 0.8382)
			(stroke
				(width 0.1524)
				(type default)
			)
			(layer "F.SilkS")
		)
		(fp_line
			(start 1.016 2.2352)
			(end -1.016 2.2352)
			(stroke
				(width 0.1524)
				(type default)
			)
			(layer "F.SilkS")
		)
		(fp_line
			(start 1.016 0.8382)
			(end 1.016 2.2352)
			(stroke
				(width 0.1524)
				(type default)
			)
			(layer "F.SilkS")
		)
		(fp_line
			(start -1.016 -0.8382)
			(end -1.016 -2.2352)
			(stroke
				(width 0.1524)
				(type default)
			)
			(layer "F.SilkS")
		)
		(fp_line
			(start -1.016 -2.2352)
			(end 1.016 -2.2352)
			(stroke
				(width 0.1524)
				(type default)
			)
			(layer "F.SilkS")
		)
		(fp_line
			(start 1.016 -2.2352)
			(end 1.016 -0.8382)
			(stroke
				(width 0.1524)
				(type default)
			)
			(layer "F.SilkS")
		)
		(fp_rect
			(start -1.0922 2.3114)
			(end 1.0922 -2.3114)
			(stroke
				(width 0)
				(type default)
			)
			(fill no)
			(layer "F.CrtYd")
		)
		(fp_poly
			(pts
				(xy 1.0922 -2.3114) (xy 1.0922 2.3114) (xy -1.0922 2.3114) (xy -1.0922 -2.3114)
			)
			(stroke
				(width 0)
				(type default)
			)
			(fill no)
			(layer "F.Fab")
		)
		(pad "1" smd rect
			(at 0 -1.397 270)
			(size 1.651 1.27)
			(layers "F.Cu" "F.Mask" "F.Paste")
			(net "P5V_HDD15")
		)
		(pad "2" smd rect
			(at 0 1.397 270)
			(size 1.651 1.27)
			(layers "F.Cu" "F.Mask" "F.Paste")
			(net "GND")
		)
	)
	(footprint ""
		(layer "F.Cu")
		(at 46.265846 -294.683942 -90)
		(property "Reference" "C59"
			(at 0 0 270)
			(layer "F.SilkS")
			(hide yes)
			(effects
				(font
					(size 1.27 1.27)
				)
			)
		)
		(property "Value" "SC4D7U25V5KX-1-GP"
			(at -0.0762 -6.1214 270)
			(unlocked yes)
			(layer "F.Fab")
			(hide yes)
			(effects
				(font
					(size 1.016 1.016)
					(thickness 0.1524)
				)
			)
		)
		(property "Device Type" "C805H58"
			(at -0.0762 -8.1534 270)
			(unlocked yes)
			(layer "F.Fab")
			(hide yes)
			(effects
				(font
					(size 1.016 1.016)
					(thickness 0.1524)
				)
			)
		)
		(duplicate_pad_numbers_are_jumpers no)
		(fp_line
			(start 0.635 0)
			(end -0.635 0)
			(stroke
				(width 0.508)
				(type default)
			)
			(layer "F.SilkS")
		)
		(fp_rect
			(start -0.9652 1.778)
			(end 0.9652 -1.778)
			(stroke
				(width 0)
				(type default)
			)
			(fill no)
			(layer "F.CrtYd")
		)
		(fp_poly
			(pts
				(xy -0.9652 -1.778) (xy 0.9652 -1.778) (xy 0.9652 1.778) (xy -0.9652 1.778)
			)
			(stroke
				(width 0)
				(type default)
			)
			(fill no)
			(layer "F.Fab")
		)
		(pad "1" smd rect
			(at 0 -0.9652 270)
			(size 1.397 1.143)
			(layers "F.Cu" "F.Mask" "F.Paste")
			(net "P12V_HDD1")
		)
		(pad "2" smd rect
			(at 0 0.9652 270)
			(size 1.397 1.143)
			(layers "F.Cu" "F.Mask" "F.Paste")
			(net "GND")
		)
	)
	(footprint ""
		(layer "F.Cu")
		(at 180.7464 -48.554894 90)
		(property "Reference" "R810"
			(at 0 0 90)
			(layer "F.SilkS")
			(hide yes)
			(effects
				(font
					(size 1.27 1.27)
				)
			)
		)
		(property "Value" "4K7R2J-2-GP"
			(at 0.064008 -3.993896 90)
			(unlocked yes)
			(layer "F.Fab")
			(hide yes)
			(effects
				(font
					(size 1.016 1.016)
					(thickness 0.1524)
				)
			)
		)
		(property "Device Type" "R402H16"
			(at 0.064008 -5.517896 90)
			(unlocked yes)
			(layer "F.Fab")
			(hide yes)
			(effects
				(font
					(size 1.016 1.016)
					(thickness 0.1524)
				)
			)
		)
		(duplicate_pad_numbers_are_jumpers no)
		(fp_line
			(start 0.508 -0.9398)
			(end -0.508 -0.9398)
			(stroke
				(width 0.1524)
				(type default)
			)
			(layer "F.SilkS")
		)
		(fp_line
			(start -0.508 -0.9398)
			(end -0.508 0.9398)
			(stroke
				(width 0.1524)
				(type default)
			)
			(layer "F.SilkS")
		)
		(fp_rect
			(start -0.508 0.9398)
			(end 0.508 -0.9398)
			(stroke
				(width 0)
				(type default)
			)
			(fill no)
			(layer "F.CrtYd")
		)
		(fp_rect
			(start -0.508 0.9398)
			(end 0.508 -0.9398)
			(stroke
				(width 0)
				(type default)
			)
			(fill no)
			(layer "F.Fab")
		)
		(pad "1" smd custom
			(at 0 -0.4445 90)
			(size 0.1397 0.1397)
			(layers "F.Cu" "F.Mask" "F.Paste")
			(net "SW_PWR_R_HDD29")
			(options
				(clearance outline)
				(anchor circle)
			)
			(primitives
				(gr_poly
					(pts
						(arc
							(start -0.1778 -0.2794)
							(mid -0.249642 -0.249642)
							(end -0.2794 -0.1778)
						)
						(arc
							(start -0.2794 0.1778)
							(mid -0.249642 0.249642)
							(end -0.1778 0.2794)
						)
						(arc
							(start 0.1778 0.2794)
							(mid 0.249642 0.249642)
							(end 0.2794 0.1778)
						)
						(arc
							(start 0.2794 -0.1778)
							(mid 0.249642 -0.249642)
							(end 0.1778 -0.2794)
						)
					)
					(width 0)
					(fill yes)
				)
			)
		)
		(pad "2" smd custom
			(at 0 0.4445 90)
			(size 0.1397 0.1397)
			(layers "F.Cu" "F.Mask" "F.Paste")
			(net "GND")
			(options
				(clearance outline)
				(anchor circle)
			)
			(primitives
				(gr_poly
					(pts
						(arc
							(start -0.1778 -0.2794)
							(mid -0.249642 -0.249642)
							(end -0.2794 -0.1778)
						)
						(arc
							(start -0.2794 0.1778)
							(mid -0.249642 0.249642)
							(end -0.1778 0.2794)
						)
						(arc
							(start 0.1778 0.2794)
							(mid 0.249642 0.249642)
							(end 0.2794 0.1778)
						)
						(arc
							(start 0.2794 -0.1778)
							(mid 0.249642 -0.249642)
							(end 0.1778 -0.2794)
						)
					)
					(width 0)
					(fill yes)
				)
			)
		)
	)
	(footprint ""
		(layer "F.Cu")
		(at 363.655102 -275.252942 -90)
		(property "Reference" "Q43"
			(at 0 0 270)
			(layer "F.SilkS")
			(hide yes)
			(effects
				(font
					(size 1.27 1.27)
				)
			)
		)
		(property "Value" "2N7002KDW-GP"
			(at -2.3622 -8.2042 270)
			(unlocked yes)
			(layer "F.Fab")
			(hide yes)
			(effects
				(font
					(size 1.016 1.016)
					(thickness 0.1524)
				)
			)
		)
		(property "Device Type" "SOT-363H44"
			(at -2.3622 -10.1092 270)
			(unlocked yes)
			(layer "F.Fab")
			(hide yes)
			(effects
				(font
					(size 1.016 1.016)
					(thickness 0.1524)
				)
			)
		)
		(duplicate_pad_numbers_are_jumpers no)
		(fp_line
			(start -1.4478 1.7018)
			(end 1.4478 1.7018)
			(stroke
				(width 0.1524)
				(type default)
			)
			(layer "F.SilkS")
		)
		(fp_line
			(start 1.4478 1.7018)
			(end 1.4478 -1.7018)
			(stroke
				(width 0.1524)
				(type default)
			)
			(layer "F.SilkS")
		)
		(fp_line
			(start -1.27 1.524)
			(end -1.27 0.6604)
			(stroke
				(width 0.4826)
				(type default)
			)
			(layer "F.SilkS")
		)
		(fp_line
			(start -1.4478 -1.7018)
			(end -1.4478 1.7018)
			(stroke
				(width 0.1524)
				(type default)
			)
			(layer "F.SilkS")
		)
		(fp_line
			(start 1.4478 -1.7018)
			(end -1.4478 -1.7018)
			(stroke
				(width 0.1524)
				(type default)
			)
			(layer "F.SilkS")
		)
		(fp_poly
			(pts
				(xy -1.524 -1.778) (xy 1.524 -1.778) (xy 1.524 1.778) (xy -1.524 1.778)
			)
			(stroke
				(width 0)
				(type default)
			)
			(fill no)
			(layer "F.CrtYd")
		)
		(fp_poly
			(pts
				(xy -1.524 -1.778) (xy 1.524 -1.778) (xy 1.524 1.778) (xy -1.524 1.778)
			)
			(stroke
				(width 0)
				(type default)
			)
			(fill no)
			(layer "F.Fab")
		)
		(pad "1" smd rect
			(at -0.65024 0.9398 270)
			(size 0.4064 1.016)
			(layers "F.Cu" "F.Mask" "F.Paste")
			(net "GND")
		)
		(pad "2" smd rect
			(at 0 0.9398 270)
			(size 0.4064 1.016)
			(layers "F.Cu" "F.Mask" "F.Paste")
			(net "SW_PWR_R_HDD7")
		)
		(pad "3" smd rect
			(at 0.65024 0.9398 270)
			(size 0.4064 1.016)
			(layers "F.Cu" "F.Mask" "F.Paste")
			(net "SW_HDD_P7")
		)
		(pad "4" smd rect
			(at 0.65024 -0.9398 270)
			(size 0.4064 1.016)
			(layers "F.Cu" "F.Mask" "F.Paste")
			(net "GND")
		)
		(pad "5" smd rect
			(at 0 -0.9398 270)
			(size 0.4064 1.016)
			(layers "F.Cu" "F.Mask" "F.Paste")
			(net "SW_HDD_G7")
		)
		(pad "6" smd rect
			(at -0.65024 -0.9398 270)
			(size 0.4064 1.016)
			(layers "F.Cu" "F.Mask" "F.Paste")
			(net "SW_HDD_R7")
		)
	)
)
